-- pcdb file, Rev:1.0 written by VAN 1.03-a8 on Sep 30, 1997  16:53:11
